FILE_TYPE = CONNECTIVITY;
{Allegro Design Entry HDL 17.4-2019 S026 (4007227) 1/17/2022}
"PAGE_NUMBER" = 28;
0"NC";
1"GND\g";
2"GND\g";
3"GND\g";
4"GND\g";
5"GND\g";
6"GND\g";
7"GND\g";
8"GND\g";
9"PVDD18_S5_P0\g";
10"IRQ_SMI_ACTIVE_N";
11"IRQ_BMC_SMI_N";
12"IRQ_TPM_SPI_R_N";
13"FM_BOARD_SKU_ID4";
14"CPU0_ROM_TYPE_SELECT";
15"FM_BOARD_SKU_ID3";
16"FM_BOARD_SKU_ID2";
17"BIOS_DEBUG_MODE";
18"BOOT_RDY_R_H";
19"FM_BIOS_POST_CMPLT_R_N";
20"FM_BOARD_SKU_ID1";
21"XTAL_CPU0_X48M_X2_R";
22"XTAL_CPU0_X48M_X1";
23"CPU0_FORCE_SELFREFRESH";
24"SMB_CPU_5_R_SCL";
25"SMB_CPU_5_SCL";
26"CLK_100M_CPU0_CLK12_DN";
27"CLK_100M_CPU0_CLK13_DN";
28"CLK_100M_CPU0_CLK12_DP";
29"CLK_100M_CPU0_CLK05_DN";
30"CLK_100M_CPU0_CLK05_DP";
31"CLK_100M_CPU0_CLK04_DN";
32"CLK_100M_CPU0_CLK11_DP";
33"CLK_100M_CPU0_CLK11_DN";
34"CLK_100M_CPU0_CLK12_R_DP";
35"CLK_100M_CPU0_CLK04_R_DN";
36"CLK_100M_CPU0_CLK13_R_DP";
37"CLK_100M_CPU0_CLK13_R_DN";
38"CLK_100M_CPU0_CLK12_R_DN";
39"CLK_100M_CPU0_CLK05_R_DP";
40"CLK_100M_CPU0_CLK03_DP";
41"SMB_CPU0_SEC_SCL";
42"PVDD18_S5_P0\g";
43"PVDD18_S5_P0\g";
44"GND\g";
45"PVDD11_S3_P0\g";
46"PVDD11_S3_P0\g";
47"CLK_100M_CPU0_CLK11_R_DN";
48"CLK_100M_CPU0_CLK11_R_DP";
49"CLK_100M_CPU0_CLK02_DP";
50"CLK_100M_CPU0_CLK04_DP";
51"FM_INT_CPU0_HP_UBM_N";
52"XTAL_CPU0_X48M_X2";
53"CPU0_NV_SAVE_N";
54"CPU0_SPD_HOST_CTRL_N";
55"CPU0_SMERR_N";
56"CPU0_NMI_SYNC_FLOOD_N";
57"PWRGD_CPU0_PWROK";
58"RST_CPU0_RESETL_N";
59"FM_SMM_CRASHDUMP";
60"CPU0_PWR_GD_OUT";
61"CPU0_SLP_S3_N";
62"CPU0_SLP_S5_N";
63"RST_CPU0_RSMRST_N";
64"CPU0_PWR_GOOD";
65"FM_INT_CPU0_HP_UBM_N";
66"RST_CPU0_PERST1_N";
67"CLK_100M_CPU0_CLK01_R_DP";
68"IRQ_WAKE_N";
69"RST_CPU0_PERST0_N";
70"IRQ_SMI_ACTIVE_N";
71"FAB_REV_ID2";
72"FAB_REV_ID1";
73"FAB_REV_ID0";
74"SMB_CPU0_SEC_SDA";
75"CPU0_NMI_SYNC_FLOOD_N";
76"BOOT_RDY_H";
77"CPU0_PWR_BTN_N";
78"RST_CPU0_SYS_N";
79"CLK_100M_CPU0_CLK02_R_DP";
80"CLK_100M_CPU0_CLK04_R_DP";
81"CLK_100M_CPU0_CLK03_R_DN";
82"CLK_100M_CPU0_CLK01_R_DN";
83"CLK_100M_CPU0_CLK03_R_DP";
84"CLK_100M_CPU0_CLK05_R_DN";
85"RST_CPU0_RESETL_N";
86"PWRGD_CPU0_PWROK";
87"CLK_CPU0_RTCCLK";
88"CPU0_PWR_BTN_N";
89"CLK_100M_CPU0_CLK02_R_DN";
90"CPU0_NV_SAVE_N";
91"CLK_100M_CPU0_CLK02_DN";
92"CLK_100M_CPU0_CLK01_DP";
93"CLK_100M_CPU0_CLK03_DN";
94"CLK_100M_CPU0_CLK01_DN";
95"XTAL_CPU0_X32K_X2";
96"CPU0_SMERR_N";
97"RST_CPU0_SYS_N";
98"RST_CPU0_SYS_N";
99"CPU0_PWR_BTN_N";
100"XTAL_CPU0_X48M_X1";
101"RST_CPU0_RSMRST_N";
102"CPU0_PWR_GOOD";
103"XTAL_CPU0_X32K_X1";
104"I3C_0_SPD_DDRAF_CPU0_R_SDA";
105"I3C_0_SPD_DDRAF_CPU0_R_SCL";
106"CLK_100M_REF_IN_DN";
107"CLK_100M_REF_OUT_DN";
108"CLK_100M_REF_IN_DP";
109"CLK_100M_REF_OUT_DP";
110"SMB_CPU0_2_R_SDA";
111"SMB_CPU0_3_R_SCL";
112"SMB_CPU0_3_R_SDA";
113"CPU0_SLP_S5_N";
114"FM_CPU0_SLP_S5_N";
115"CPU0_SLP_S3_N";
116"FM_CPU0_SLP_S3_N";
117"CPU1_PWR_GD_IN";
118"CPU0_PWR_GD_OUT";
119"SMB_CPU0_2_R_SCL";
120"CPU0_FORCE_SELFREFRESH";
121"I3C_0_SPD_DDRAF_CPU0_R_SCL";
122"I3C_0_SPD_DDRAF_CPU0_R_SDA";
123"I3C_1_SPD_DDRGL_CPU0_R_SCL";
124"FM_BIOS_POST_CMPLT_N";
125"I3C_1_SPD_DDRGL_CPU0_R_SDA";
126"SMB_CPU_5_R_SDA";
127"XTAL_CPU0_X48M_X2";
128"FM_PASSWORD_CLEAR_R_N";
129"IRQ_TPM_SPI_R_N";
130"FM_BOARD_SKU_ID0";
131"BOOT_RDY_H";
132"CPU0_FORCE_SELFREFRESH";
133"I3C_1_SPD_DDRGL_CPU0_R_SDA";
134"CLK_100M_CPU0_CLK13_DP";
135"XTAL_CPU0_X32K_X1";
136"XTAL_CPU0_X32K_X2";
137"SMB_CPU0_3_SCL";
138"SMB_CPU0_4_R_SDA";
139"SMB_CPU0_4_R_SCL";
140"I3C_1_SPD_DDRGL_CPU0_R_SCL";
141"SMB_CPU0_2_SCL";
142"SMB_CPU0_3_SDA";
143"SMB_CPU0_4_SCL";
144"SMB_CPU0_4_SDA";
145"SMB_CPU_5_SDA";
146"FM_PASSWORD_CLEAR_N";
147"IRQ_BMC_SMI_N";
148"FM_SMM_CRASHDUMP";
149"CPU0_SPD_HOST_CTRL_N";
150"SMB_CPU0_2_SDA";
151"GND\g";
152"GND\g";
153"GND\g";
154"GND\g";
155"GND\g";
156"GND\g";
157"GND\g";
%"Q_RES"
"1","(-6375,10325)","2","pure_quanta","I100";
;
LOCATION"R1205"
$SEC"1"
CDS_SEC"1"
VALUE"0"
PACK_TYPE"0402LF"
TOLERANCE"5%"
MATERIAL"CHIP"
WATTAGE"1/16W"
CDS_LIB"pure_quanta"
PART_NUMBER"CS00002JB13";
"B"
$PN"2"146;
"A"
$PN"1"128;
%"UNIVERSAL_GND"
"1","(-5950,8325)","0","pure_quanta_power","I102";
;
CDS_LIB"pure_quanta_power"
HDL_POWER"GND";
"A"1;
%"Q_XTAL_4P_13BI_24GND"
"1","(-5575,8650)","0","pure_quanta","I103";
;
LOCATION"Y2"
$SEC"1"
CDS_SEC"1"
VALUE"48MHZ"
PART_TYPE"SMLF"
MATERIAL"MISC"
PIN_NAMES_ROTATE"True"
CDS_LMAN_SYM_OUTLINE"-125,175,125,-175"
CDS_LIB"pure_quanta"
PART_NUMBER"BG648000076";
"X2"
$PN"3"21;
"G2"
$PN"4"2;
"G1"
$PN"2"1;
"X1"
$PN"1"22;
%"Q_RES"
"1","(-5575,8125)","0","pure_quanta","I104";
;
LOCATION"R432"
$SEC"1"
CDS_SEC"1"
WATTAGE"1/16W"
TOLERANCE"1%"
MATERIAL"CHIP"
PACK_TYPE"0402LF"
VALUE"10M"
CDS_LIB"pure_quanta"
PART_NUMBER"CS61002FB02";
"B"
$PN"2"21;
"A"
$PN"1"22;
%"UNIVERSAL_GND"
"1","(-5150,8300)","0","pure_quanta_power","I105";
;
CDS_LIB"pure_quanta_power"
HDL_POWER"GND";
"A"2;
%"UNIVERSAL_GND"
"1","(-4950,7600)","0","pure_quanta_power","I106";
;
CDS_LIB"pure_quanta_power"
HDL_POWER"GND";
"A"3;
%"Q_RES"
"1","(-6500,12625)","0","pure_quanta","I135";
;
LOCATION"R249"
$SEC"1"
CDS_SEC"1"
VALUE"33"
CDS_LIB"pure_quanta"
BOM_COST"MEM"
WATTAGE"1/16W"
MATERIAL"CHIP"
TOLERANCE"5%"
PACK_TYPE"0402LF"
PART_NUMBER"CS03302JB10";
"B"
$PN"2"115;
"A"
$PN"1"116;
%"Q_RES"
"1","(-6500,12675)","0","pure_quanta","I136";
;
LOCATION"R248"
$SEC"1"
CDS_SEC"1"
VALUE"33"
CDS_LIB"pure_quanta"
BOM_COST"MEM"
WATTAGE"1/16W"
MATERIAL"CHIP"
TOLERANCE"5%"
PACK_TYPE"0402LF"
PART_NUMBER"CS03302JB10";
"B"
$PN"2"113;
"A"
$PN"1"114;
%"UNIVERSAL_GND"
"1","(-3900,7725)","0","pure_quanta_power","I137";
;
CDS_LIB"pure_quanta_power"
HDL_POWER"GND";
"A"4;
%"Q_CRYSTAL"
"1","(-3350,8750)","0","pure_quanta","I140";
;
LOCATION"Y3"
$SEC"1"
CDS_SEC"1"
MATERIAL"IC"
VALUE"32.768KHZ"
PACK_TYPE"SMLF"
CDS_LIB"pure_quanta"
NEEDS_NO_SIZE"TRUE"
PART_NUMBER"BG632768012";
"2"
$PN"2"136;
"1"
$PN"1"135;
%"UNIVERSAL_GND"
"1","(-2800,7725)","0","pure_quanta_power","I141";
;
CDS_LIB"pure_quanta_power"
HDL_POWER"GND";
"A"5;
%"Q_RES"
"1","(-2000,11025)","0","pure_quanta","I151";
;
LOCATION"R2660"
$SEC"1"
CDS_SEC"1"
TOLERANCE"5%"
VALUE"0"
WATTAGE"1/16W"
PACK_TYPE"0402LF"
MATERIAL"CHIP"
CDS_LIB"pure_quanta"
PART_NUMBER"CS00002JB13";
"B"
$PN"2"33;
"A"
$PN"1"47;
%"Q_RES"
"1","(-2000,11075)","0","pure_quanta","I152";
;
LOCATION"R2659"
$SEC"1"
CDS_SEC"1"
WATTAGE"1/16W"
PACK_TYPE"0402LF"
VALUE"0"
TOLERANCE"5%"
CDS_LIB"pure_quanta"
MATERIAL"CHIP"
PART_NUMBER"CS00002JB13";
"B"
$PN"2"32;
"A"
$PN"1"48;
%"Q_RES"
"1","(-2000,11375)","0","pure_quanta","I153";
;
LOCATION"R9273"
$SEC"1"
CDS_SEC"1"
PACK_TYPE"0402LF"
TOLERANCE"5%"
VALUE"0"
WATTAGE"1/16W"
CDS_LIB"pure_quanta"
MATERIAL"CHIP"
PART_NUMBER"CS00002JB13";
"B"
$PN"2"50;
"A"
$PN"1"80;
%"Q_RES"
"1","(-2000,11325)","0","pure_quanta","I154";
;
LOCATION"R9274"
$SEC"1"
CDS_SEC"1"
PACK_TYPE"0402LF"
WATTAGE"1/16W"
VALUE"0"
TOLERANCE"5%"
MATERIAL"CHIP"
CDS_LIB"pure_quanta"
PART_NUMBER"CS00002JB13";
"B"
$PN"2"31;
"A"
$PN"1"35;
%"Q_RES"
"1","(-2000,11475)","0","pure_quanta","I155";
;
LOCATION"R8566"
$SEC"1"
CDS_SEC"1"
WATTAGE"1/16W"
VALUE"0"
TOLERANCE"5%"
PACK_TYPE"0402LF"
MATERIAL"CHIP"
CDS_LIB"pure_quanta"
PART_NUMBER"CS00002JB13";
"B"
$PN"2"93;
"A"
$PN"1"81;
%"Q_RES"
"1","(-2025,11625)","0","pure_quanta","I156";
;
LOCATION"R8564"
$SEC"1"
CDS_SEC"1"
PACK_TYPE"0402LF"
TOLERANCE"5%"
WATTAGE"1/16W"
VALUE"0"
MATERIAL"CHIP"
CDS_LIB"pure_quanta"
PART_NUMBER"CS00002JB13";
"B"
$PN"2"91;
"A"
$PN"1"89;
%"Q_RES"
"1","(-2025,11675)","0","pure_quanta","I157";
;
LOCATION"R8563"
$SEC"1"
CDS_SEC"1"
PACK_TYPE"0402LF"
WATTAGE"1/16W"
MATERIAL"CHIP"
VALUE"0"
TOLERANCE"5%"
CDS_LIB"pure_quanta"
PART_NUMBER"CS00002JB13";
"B"
$PN"2"49;
"A"
$PN"1"79;
%"Q_RES"
"1","(-2000,11525)","0","pure_quanta","I158";
;
LOCATION"R8565"
$SEC"1"
CDS_SEC"1"
VALUE"0"
WATTAGE"1/16W"
TOLERANCE"5%"
PACK_TYPE"0402LF"
MATERIAL"CHIP"
CDS_LIB"pure_quanta"
PART_NUMBER"CS00002JB13";
"B"
$PN"2"40;
"A"
$PN"1"83;
%"Q_RES"
"1","(-2025,11825)","0","pure_quanta","I160";
;
LOCATION"R4535"
$SEC"1"
CDS_SEC"1"
PACK_TYPE"0402LF"
TOLERANCE"5%"
VALUE"0"
MATERIAL"CHIP"
WATTAGE"1/16W"
CDS_LIB"pure_quanta"
PART_NUMBER"CS00002JB13";
"B"
$PN"2"92;
"A"
$PN"1"67;
%"Q_RES"
"1","(-2025,11775)","0","pure_quanta","I161";
;
LOCATION"R4536"
$SEC"1"
CDS_SEC"1"
TOLERANCE"5%"
VALUE"0"
WATTAGE"1/16W"
PACK_TYPE"0402LF"
CDS_LIB"pure_quanta"
MATERIAL"CHIP"
PART_NUMBER"CS00002JB13";
"B"
$PN"2"94;
"A"
$PN"1"82;
%"Q_RES"
"1","(-2175,12525)","0","pure_quanta","I165";
;
LOCATION"R434"
$SEC"1"
CDS_SEC"1"
VALUE"33"
PACK_TYPE"0402LF"
TOLERANCE"5%"
MATERIAL"CHIP"
WATTAGE"1/16W"
CDS_LIB"pure_quanta"
PART_NUMBER"CS03302JB10";
"B"
$PN"2"117;
"A"
$PN"1"118;
%"Q_RES"
"1","(-1975,11225)","0","pure_quanta","I167";
;
LOCATION"R9275"
$SEC"1"
CDS_SEC"1"
VALUE"0"
WATTAGE"1/16W"
TOLERANCE"5%"
PACK_TYPE"0402LF"
MATERIAL"CHIP"
CDS_LIB"pure_quanta"
PART_NUMBER"CS00002JB13";
"B"
$PN"2"30;
"A"
$PN"1"39;
%"Q_RES"
"1","(-1975,11175)","0","pure_quanta","I168";
;
LOCATION"R9276"
$SEC"1"
CDS_SEC"1"
VALUE"0"
TOLERANCE"5%"
WATTAGE"1/16W"
PACK_TYPE"0402LF"
MATERIAL"CHIP"
CDS_LIB"pure_quanta"
PART_NUMBER"CS00002JB13";
"B"
$PN"2"29;
"A"
$PN"1"84;
%"Q_RES"
"1","(-1800,13025)","0","pure_quanta","I171";
;
LOCATION"R435"
$SEC"1"
CDS_SEC"1"
VALUE"0"
PACK_TYPE"0402LF"
TOLERANCE"5%"
MATERIAL"CHIP"
WATTAGE"1/16W"
CDS_LIB"pure_quanta"
PART_NUMBER"CS00002JB13";
"B"
$PN"2"108;
"A"
$PN"1"109;
%"Q_RES"
"1","(-1800,12975)","0","pure_quanta","I172";
;
LOCATION"R436"
$SEC"1"
CDS_SEC"1"
VALUE"0"
PACK_TYPE"0402LF"
TOLERANCE"5%"
MATERIAL"CHIP"
WATTAGE"1/16W"
CDS_LIB"pure_quanta"
PART_NUMBER"CS00002JB13";
"B"
$PN"2"106;
"A"
$PN"1"107;
%"GENOA_SP5"
"21","(-4350,11375)","0","pure_quanta","I188";
;
LOCATION"U25"
$SEC"21"
CDS_SEC"21"
PART_TYPE"SMLF"
VALUE"SOCKET6096_13568-001"
MATERIAL"IO"
CDS_LIB"pure_quanta"
CDS_LMAN_SYM_OUTLINE"-1100,1800,1100,-1800"
NEEDS_NO_SIZE"TRUE"
PART_NUMBER"DGA^6000030";
"AGPIO7"
$PN"DH4"13;
"NMI_SYNC_FLOOD_L"
$PN"DJ31"75;
"SEC_SCL||AGPIO262"
$PN"B14"41;
"SEC_SDA||AGPIO263"
$PN"D14"74;
"AGPIO257||SGPIO1_CLK||CLK_REQ01_L"
$PN"C14"72;
"PWROK||SVI_RST_L"
$PN"D69"86;
"AGPIO6||DEVSLP1||SATA_ZP1_L"
$PN"DE40"147;
"AGPIO5||DEVSLP0||SATA_ZP0_L"
$PN"DF40"148;
"GENINT_L||PM_INTR_L||UBM_CPRSNT_CHANGE_DET_L||AGPIO89"
$PN"DJ35"51;
"AGPIO22"
$PN"DE32"20;
"AGPIO88"
$PN"DJ29"19;
"AGPIO21"
$PN"DF33"130;
"AGPIO87"
$PN"DG11"0;
"AGPIO109"
$PN"DG32"14;
"AGPIO107"
$PN"DG31"15;
"AGPIO106"
$PN"DF31"16;
"AGPIO105"
$PN"DE30"17;
"AGPIO104"
$PN"DH30"18;
"RESET_L \B"
$PN"B67"85;
"REFCLK100SSC_N||GPP_CLK10N"
$PN"A20"107;
"REFCLK100SSC_P||GPP_CLK10P"
$PN"A19"109;
"SMERR_L||AGPIO24"
$PN"DJ11"96;
"I2C5_SDA||BMC_SDA||SMBUS1_SDA||AGPIO20"
$PN"DJ20"126;
"I2C5_SCL||BMC_SCL||SMBUS1_SCL||AGPIO19"
$PN"DJ21"24;
"I2C4_SDA||HP_SDA||UBM_SDA||AGPIO14"
$PN"DH12"138;
"I2C4_SCL||HP_SCL||UBM_SCL||AGPIO13"
$PN"DG12"139;
"I3C3_SCL||I2C3_SCL||SPD3_SCL||AGPIO151"
$PN"A4"111;
"I3C1_SDA||I2C1_SDA||SPD1_SDA||AGPIO148"
$PN"A5"125;
"AGPIO116||CLK_REQ12_L"
$PN"DH15"129;
"PWRGD_OUT||AGPIO12"
$PN"DH36"118;
"AGPIO259||SGPIO3_CLK"
$PN"B16"0;
"I3C0_SCL||I2C0_SCL||SPD0_SCL||SMBUS0_SCL||AGPIO145"
$PN"A71"105;
"I3C2_SCL||I2C2_SCL||SPD2_SCL||AGPIO149"
$PN"C72"119;
"I3C1_SCL||I2C1_SCL||SPD1_SCL||AGPIO147"
$PN"C7"140;
"I3C0_SDA||I2C0_SDA||SPD0_SDA||SMBUS0_SDA||AGPIO146"
$PN"B71"104;
"AGPIO115||CLK_REQ11_L"
$PN"DH16"70;
"PCIE_RST0_L||AGPIO266"
$PN"D18"69;
"AGPIO256||SGPIO0_CLK"
$PN"A14"73;
"AGPIO258||SGPIO2_CLK||CLK_REQ02_L"
$PN"A13"71;
"I3C3_SDA||I2C3_SDA||SPD3_SDA||AGPIO152"
$PN"B4"112;
"SGPIO_DATAOUT||AGPIO260"
$PN"D15"0;
"I3C2_SDA||I2C2_SDA||SPD2_SDA||AGPIO150"
$PN"B72"110;
"SGPIO_LOAD||AGPIO261"
$PN"B15"0;
"PCIE_RST1_L||AGPIO26"
$PN"DG36"66;
"AGPIO3||SPD_HOST_CTRL_L"
$PN"DE36"149;
"AGPIO4||SATA_ACT_L"
$PN"DF36"128;
"GPP_CLK11P"
$PN"DJ41"48;
"GPP_CLK01P"
$PN"A8"67;
"GPP_CLK12P"
$PN"DJ45"34;
"GPP_CLK02P"
$PN"B6"79;
"GPP_CLK11N"
$PN"DJ42"47;
"GPP_CLK13P"
$PN"DJ53"36;
"GPP_CLK01N"
$PN"A7"82;
"GPP_CLK03P"
$PN"A10"83;
"GPP_CLK12N"
$PN"DJ44"38;
"GPP_CLK14P"
$PN"DJ48"0;
"GPP_CLK02N"
$PN"C6"89;
"GPP_CLK04P"
$PN"B12"80;
"GPP_CLK13N"
$PN"DJ54"37;
"GPP_CLK15P"
$PN"DJ51"0;
"GPP_CLK03N"
$PN"A11"81;
"GPP_CLK05P"
$PN"B9"39;
"GPP_CLK14N"
$PN"DJ47"0;
"GPP_CLK04N"
$PN"C12"35;
"GPP_CLK15N"
$PN"DJ50"0;
"GPP_CLK05N"
$PN"C9"84;
"RTCCLK"
$PN"DH9"87;
"FORCE_SELFREFRESH"
$PN"B63"120;
"NV_SAVE_L"
$PN"B64"90;
"PWR_BTN_L||AGPIO0"
$PN"DH7"88;
"X48M_X2"
$PN"DJ16"127;
"X48M_X1"
$PN"DJ17"100;
"X32K_X2"
$PN"DJ13"95;
"X32K_X1"
$PN"DJ14"103;
"WAKE_L||AGPIO2"
$PN"DJ10"68;
"SYS_RESET_L||AGPIO1"
$PN"DH6"78;
"SLP_S5_L"
$PN"DG4"113;
"SLP_S3_L"
$PN"DJ5"115;
"RSMRST_L \B"
$PN"DG10"101;
"PWR_GOOD"
$PN"DJ8"102;
%"Q_RES"
"1","(-2000,10925)","0","pure_quanta","I191";
;
LOCATION"R4303"
$SEC"1"
CDS_SEC"1"
VALUE"0"
PACK_TYPE"0402LF"
WATTAGE"1/16W"
TOLERANCE"5%"
CDS_LIB"pure_quanta"
MATERIAL"CHIP"
PART_NUMBER"CS00002JB13";
"B"
$PN"2"28;
"A"
$PN"1"34;
%"Q_RES"
"1","(-2000,10875)","0","pure_quanta","I192";
;
LOCATION"R4304"
$SEC"1"
CDS_SEC"1"
TOLERANCE"5%"
VALUE"0"
WATTAGE"1/16W"
PACK_TYPE"0402LF"
CDS_LIB"pure_quanta"
MATERIAL"CHIP"
PART_NUMBER"CS00002JB13";
"B"
$PN"2"26;
"A"
$PN"1"38;
%"UNIVERSAL_GND"
"1","(-7125,12050)","0","pure_quanta_power","I193";
;
CDS_LIB"pure_quanta_power"
HDL_POWER"GND";
"A"6;
%"Q_CAP"
"1","(-7125,12250)","0","pure_quanta","I194";
;
LOCATION"C5023"
$SEC"1"
CDS_SEC"1"
PACK_TYPE"0402"
MATERIAL"X7R"
VALUE"1000PF"
TOLERANCE"5%"
VOLTAGE"50V"
CDS_LIB"pure_quanta"
PART_NUMBER"TMP_QCH21006JB10";
"B"
$PN"2"6;
"A"
$PN"1"101;
%"Q_RES"
"2","(-4950,8925)","2","pure_quanta","I195";
;
LOCATION"R5102"
$SEC"1"
CDS_SEC"1"
VALUE"49.9"
CDS_LIB"pure_quanta"
MATERIAL"CHIP"
PACK_TYPE"0402LF"
WATTAGE"1/16W"
TOLERANCE"1%"
PART_NUMBER"CS04992FB07";
"A"
$PN"1"52;
"B"
$PN"2"21;
%"Q_RES"
"1","(-6850,11125)","2","pure_quanta","I206";
;
LOCATION"R27"
$SEC"1"
CDS_SEC"1"
VALUE"0"
CDS_LIB"pure_quanta"
WATTAGE"1/16W"
MATERIAL"CHIP"
TOLERANCE"5%"
PACK_TYPE"0402LF"
PART_NUMBER"CS00002JB13";
"B"
$PN"2"141;
"A"
$PN"1"119;
%"Q_RES"
"1","(-6850,11075)","2","pure_quanta","I207";
;
LOCATION"R28"
$SEC"1"
CDS_SEC"1"
VALUE"0"
CDS_LIB"pure_quanta"
WATTAGE"1/16W"
MATERIAL"CHIP"
TOLERANCE"5%"
PACK_TYPE"0402LF"
PART_NUMBER"CS00002JB13";
"B"
$PN"2"150;
"A"
$PN"1"110;
%"Q_RES"
"1","(-6850,11025)","2","pure_quanta","I208";
;
LOCATION"R29"
$SEC"1"
CDS_SEC"1"
VALUE"0"
CDS_LIB"pure_quanta"
WATTAGE"1/16W"
MATERIAL"CHIP"
TOLERANCE"5%"
PACK_TYPE"0402LF"
PART_NUMBER"CS00002JB13";
"B"
$PN"2"137;
"A"
$PN"1"111;
%"Q_RES"
"1","(-6850,10975)","2","pure_quanta","I209";
;
LOCATION"R30"
$SEC"1"
CDS_SEC"1"
VALUE"0"
CDS_LIB"pure_quanta"
WATTAGE"1/16W"
MATERIAL"CHIP"
TOLERANCE"5%"
PACK_TYPE"0402LF"
PART_NUMBER"CS00002JB13";
"B"
$PN"2"142;
"A"
$PN"1"112;
%"Q_RES"
"1","(-8275,11125)","0","pure_quanta","I210";
;
LOCATION"R6081"
$SEC"1"
CDS_SEC"1"
VALUE"4.7K"
CDS_LIB"pure_quanta"
WATTAGE"1/16W"
MATERIAL"CHIP"
TOLERANCE"5%"
PACK_TYPE"0402LF"
PART_NUMBER"CS24702JB10";
"B"
$PN"2"141;
"A"
$PN"1"46;
%"VCC_CORE"
"1","(-8475,11375)","0","pure_quanta_power","I211";
;
HDL_POWER"PVDD11_S3_P0"
CDS_LIB"pure_quanta_power";
"A"46;
%"Q_RES"
"1","(-8275,11075)","0","pure_quanta","I212";
;
LOCATION"R6082"
$SEC"1"
CDS_SEC"1"
VALUE"4.7K"
CDS_LIB"pure_quanta"
WATTAGE"1/16W"
MATERIAL"CHIP"
TOLERANCE"5%"
PACK_TYPE"0402LF"
PART_NUMBER"CS24702JB10";
"B"
$PN"2"150;
"A"
$PN"1"46;
%"Q_RES"
"1","(-8275,11025)","0","pure_quanta","I213";
;
LOCATION"R6083"
$SEC"1"
CDS_SEC"1"
VALUE"4.7K"
CDS_LIB"pure_quanta"
WATTAGE"1/16W"
MATERIAL"CHIP"
TOLERANCE"5%"
PACK_TYPE"0402LF"
PART_NUMBER"CS24702JB10";
"B"
$PN"2"137;
"A"
$PN"1"46;
%"Q_RES"
"1","(-8275,10975)","0","pure_quanta","I214";
;
LOCATION"R6084"
$SEC"1"
CDS_SEC"1"
VALUE"4.7K"
CDS_LIB"pure_quanta"
WATTAGE"1/16W"
MATERIAL"CHIP"
TOLERANCE"5%"
PACK_TYPE"0402LF"
PART_NUMBER"CS24702JB10";
"B"
$PN"2"142;
"A"
$PN"1"46;
%"Q_RES"
"2","(-9100,9650)","0","pure_quanta","I22";
;
LOCATION"R420"
$SEC"1"
CDS_SEC"1"
TOLERANCE"1%"
VALUE"1K"
MATERIAL"EMPTY"
CDS_LIB"pure_quanta"
WATTAGE"1/16W"
PACK_TYPE"0402LF"
PART_NUMBER"CS21002FB06";
"A"
$PN"1"45;
"B"
$PN"2"133;
%"Q_RES"
"1","(-3350,8450)","0","pure_quanta","I221";
;
LOCATION"R433"
SEC"1"
PACK_TYPE"0402LF"
VALUE"20M"
WATTAGE"1/16W"
TOLERANCE"1%"
MATERIAL"CHIP"
SEC_TYPE"0402LF"
CDS_LIB"pure_quanta"
PART_NUMBER"CS62002FB01";
"B"
$PN"2"136;
"A"
$PN"1"135;
%"Q_RES"
"1","(-7775,8925)","0","pure_quanta","I222";
;
LOCATION"R438"
SEC"1"
VALUE"4.7K"
MATERIAL"EMPTY"
TOLERANCE"5%"
WATTAGE"1/16W"
PACK_TYPE"0402LF"
SEC_TYPE"0402LF"
CDS_LIB"pure_quanta"
PART_NUMBER"CS24702JB10";
"B"
$PN"2"42;
"A"
$PN"1"132;
%"Q_RES"
"2","(-6350,8675)","2","pure_quanta","I224";
;
LOCATION"R6502"
$SEC"1"
CDS_SEC"1"
MATERIAL"CHIP"
VALUE"2.2K"
TOLERANCE"5%"
WATTAGE"1/16W"
PACK_TYPE"0402LF"
CDS_LIB"pure_quanta"
PART_NUMBER"CS22202JB07";
"A"
$PN"1"23;
"B"
$PN"2"7;
%"UNIVERSAL_GND"
"1","(-6350,8225)","0","pure_quanta_power","I225";
;
CDS_LIB"pure_quanta_power"
HDL_POWER"GND";
"A"7;
%"Q_RES"
"1","(-2000,10725)","0","pure_quanta","I228";
;
LOCATION"R8306"
SEC"1"
TOLERANCE"5%"
WATTAGE"1/16W"
VALUE"0"
PACK_TYPE"0402LF"
SEC_TYPE"0402LF"
MATERIAL"CHIP"
CDS_LIB"pure_quanta"
PART_NUMBER"CS00002JB13";
"B"
$PN"2"27;
"A"
$PN"1"37;
%"Q_RES"
"1","(-2000,10775)","0","pure_quanta","I229";
;
LOCATION"R8305"
SEC"1"
VALUE"0"
TOLERANCE"5%"
PACK_TYPE"0402LF"
WATTAGE"1/16W"
SEC_TYPE"0402LF"
MATERIAL"CHIP"
CDS_LIB"pure_quanta"
PART_NUMBER"CS00002JB13";
"B"
$PN"2"134;
"A"
$PN"1"36;
%"Q_RES"
"2","(-8925,9650)","0","pure_quanta","I23";
;
LOCATION"R421"
$SEC"1"
CDS_SEC"1"
TOLERANCE"1%"
MATERIAL"EMPTY"
VALUE"1K"
PACK_TYPE"0402LF"
WATTAGE"1/16W"
CDS_LIB"pure_quanta"
PART_NUMBER"CS21002FB06";
"A"
$PN"1"45;
"B"
$PN"2"123;
%"Q_CAP"
"1","(-3900,8050)","0","pure_quanta","I230";
;
LOCATION"C215"
$SEC"1"
CDS_SEC"1"
VOLTAGE"50V"
PACK_TYPE"C0402"
MATERIAL"NP0"
TOLERANCE"0.1P"
VALUE"8.2PF"
CDS_LIB"pure_quanta"
PART_NUMBER"CH-8216TB09";
"B"
$PN"2"4;
"A"
$PN"1"135;
%"Q_CAP"
"1","(-2800,8075)","0","pure_quanta","I231";
;
LOCATION"C216"
$SEC"1"
CDS_SEC"1"
VOLTAGE"50V"
PACK_TYPE"C0402"
MATERIAL"NP0"
TOLERANCE"0.1P"
VALUE"8.2PF"
CDS_LIB"pure_quanta"
PART_NUMBER"CH-8216TB09";
"B"
$PN"2"5;
"A"
$PN"1"136;
%"Q_CAP"
"1","(-6225,7900)","0","pure_quanta","I232";
;
LOCATION"C213"
$SEC"1"
CDS_SEC"1"
PACK_TYPE"C0402"
VALUE"3.9P"
TOLERANCE"0.1P"
VOLTAGE"50V"
MATERIAL"NPO"
CDS_LIB"pure_quanta"
PART_NUMBER"CH-3916TB01";
"B"
$PN"2"8;
"A"
$PN"1"22;
%"Q_CAP"
"1","(-4950,7900)","0","pure_quanta","I233";
;
LOCATION"C214"
$SEC"1"
CDS_SEC"1"
PACK_TYPE"C0402"
VALUE"3.9P"
MATERIAL"NPO"
VOLTAGE"50V"
TOLERANCE"0.1P"
CDS_LIB"pure_quanta"
PART_NUMBER"CH-3916TB01";
"B"
$PN"2"3;
"A"
$PN"1"21;
%"Q_RES"
"2","(-8750,9650)","0","pure_quanta","I24";
;
LOCATION"R423"
$SEC"1"
CDS_SEC"1"
TOLERANCE"1%"
MATERIAL"EMPTY"
VALUE"1K"
PACK_TYPE"0402LF"
WATTAGE"1/16W"
CDS_LIB"pure_quanta"
PART_NUMBER"CS21002FB06";
"A"
$PN"1"45;
"B"
$PN"2"122;
%"Q_RES"
"2","(-8575,9650)","0","pure_quanta","I25";
;
LOCATION"R425"
$SEC"1"
CDS_SEC"1"
TOLERANCE"1%"
MATERIAL"EMPTY"
VALUE"1K"
CDS_LIB"pure_quanta"
PACK_TYPE"0402LF"
WATTAGE"1/16W"
PART_NUMBER"CS21002FB06";
"A"
$PN"1"45;
"B"
$PN"2"121;
%"VCC_CORE"
"1","(-8575,9950)","0","pure_quanta_power","I26";
;
HDL_POWER"PVDD11_S3_P0"
CDS_LIB"pure_quanta_power";
"A"45;
%"UNIVERSAL_GND"
"1","(-9125,11950)","0","pure_quanta_power","I27";
;
CDS_LIB"pure_quanta_power"
HDL_POWER"GND";
"A"44;
%"CONN6_HBC1031L200D8H"
"1","(-8750,12225)","2","pure_quanta","I28";
;
LOCATION"J6"
$SEC"1"
CDS_SEC"1"
VALUE"CONN6_HBC1031-L200D-8H"
MATERIAL"IO"
PART_TYPE"THLF"
CDS_LMAN_SYM_OUTLINE"-125,150,125,-150"
NEEDS_NO_SIZE"TRUE"
CDS_LIB"pure_quanta"
PART_NUMBER"DFHD06MS263";
"6"
$PN"6"44;
"5"
$PN"5"0;
"4"
$PN"4"44;
"3"
$PN"3"97;
"2"
$PN"2"44;
"1"
$PN"1"77;
%"Q_RES"
"2","(-8775,13050)","0","pure_quanta","I29";
;
LOCATION"R422"
$SEC"1"
CDS_SEC"1"
VALUE"2.2K"
PACK_TYPE"0402LF"
WATTAGE"1/16W"
CDS_LIB"pure_quanta"
TOLERANCE"5%"
MATERIAL"CHIP"
PART_NUMBER"CS22202JB07";
"A"
$PN"1"43;
"B"
$PN"2"98;
%"Q_RES"
"2","(-8600,13050)","0","pure_quanta","I30";
;
LOCATION"R424"
$SEC"1"
CDS_SEC"1"
VALUE"2.2K"
CDS_LIB"pure_quanta"
WATTAGE"1/16W"
MATERIAL"CHIP"
TOLERANCE"5%"
PACK_TYPE"0402LF"
PART_NUMBER"CS22202JB07";
"A"
$PN"1"43;
"B"
$PN"2"99;
%"UNIVERSAL_POWER"
"1","(-8600,13350)","0","pure_quanta_power","I31";
;
HDL_POWER"PVDD18_S5_P0"
CDS_LIB"pure_quanta_power";
"A"43;
%"UNIVERSAL_GND"
"1","(-7900,7075)","0","pure_quanta_power","I32";
;
CDS_LIB"pure_quanta_power"
HDL_POWER"GND";
"A"157;
%"Q_RES"
"1","(-7900,7225)","1","pure_quanta","I33";
;
LOCATION"R582"
$SEC"1"
CDS_SEC"1"
VALUE"4.7K"
MATERIAL"EMPTY"
CDS_LIB"pure_quanta"
WATTAGE"1/16W"
TOLERANCE"5%"
PACK_TYPE"0402LF"
PART_NUMBER"CS24702JB10";
"B"
$PN"2"63;
"A"
$PN"1"157;
%"Q_RES"
"1","(-7900,7775)","1","pure_quanta","I34";
;
LOCATION"R581"
$SEC"1"
CDS_SEC"1"
VALUE"4.7K"
MATERIAL"EMPTY"
CDS_LIB"pure_quanta"
WATTAGE"1/16W"
TOLERANCE"5%"
PACK_TYPE"0402LF"
PART_NUMBER"CS24702JB10";
"B"
$PN"2"9;
"A"
$PN"1"63;
%"UNIVERSAL_GND"
"1","(-7625,7075)","0","pure_quanta_power","I35";
;
CDS_LIB"pure_quanta_power"
HDL_POWER"GND";
"A"156;
%"Q_RES"
"1","(-7625,7225)","1","pure_quanta","I36";
;
LOCATION"R287"
$SEC"1"
CDS_SEC"1"
VALUE"4.7K"
MATERIAL"EMPTY"
CDS_LIB"pure_quanta"
WATTAGE"1/16W"
TOLERANCE"5%"
PACK_TYPE"0402LF"
PART_NUMBER"CS24702JB10";
"B"
$PN"2"64;
"A"
$PN"1"156;
%"Q_RES"
"1","(-7400,7225)","1","pure_quanta","I37";
;
LOCATION"R440"
$SEC"1"
CDS_SEC"1"
VALUE"4.7K"
MATERIAL"EMPTY"
PACK_TYPE"0402LF"
TOLERANCE"5%"
WATTAGE"1/16W"
CDS_LIB"pure_quanta"
PART_NUMBER"CS24702JB10";
"B"
$PN"2"60;
"A"
$PN"1"155;
%"UNIVERSAL_GND"
"1","(-7400,7075)","0","pure_quanta_power","I38";
;
CDS_LIB"pure_quanta_power"
HDL_POWER"GND";
"A"155;
%"UNIVERSAL_GND"
"1","(-7225,7075)","0","pure_quanta_power","I39";
;
CDS_LIB"pure_quanta_power"
HDL_POWER"GND";
"A"154;
%"Q_RES"
"1","(-7225,7225)","1","pure_quanta","I40";
;
LOCATION"R5026"
$SEC"1"
CDS_SEC"1"
MATERIAL"EMPTY"
VALUE"4.7K"
PACK_TYPE"0402LF"
TOLERANCE"5%"
WATTAGE"1/16W"
CDS_LIB"pure_quanta"
PART_NUMBER"CS24702JB10";
"B"
$PN"2"59;
"A"
$PN"1"154;
%"Q_RES"
"1","(-7625,7750)","1","pure_quanta","I41";
;
LOCATION"R276"
$SEC"1"
CDS_SEC"1"
VALUE"4.7K"
MATERIAL"CHIP"
PACK_TYPE"0402LF"
TOLERANCE"5%"
WATTAGE"1/16W"
CDS_LIB"pure_quanta"
PART_NUMBER"CS24702JB10";
"B"
$PN"2"9;
"A"
$PN"1"64;
%"Q_RES"
"1","(-7400,7750)","1","pure_quanta","I42";
;
LOCATION"R288"
$SEC"1"
CDS_SEC"1"
MATERIAL"EMPTY"
VALUE"4.7K"
PACK_TYPE"0402LF"
TOLERANCE"5%"
WATTAGE"1/16W"
CDS_LIB"pure_quanta"
PART_NUMBER"CS24702JB10";
"B"
$PN"2"9;
"A"
$PN"1"60;
%"Q_RES"
"1","(-7225,7750)","1","pure_quanta","I43";
;
LOCATION"R444"
$SEC"1"
CDS_SEC"1"
VALUE"4.7K"
MATERIAL"CHIP"
CDS_LIB"pure_quanta"
WATTAGE"1/16W"
TOLERANCE"5%"
PACK_TYPE"0402LF"
PART_NUMBER"CS24702JB10";
"B"
$PN"2"9;
"A"
$PN"1"59;
%"Q_RES"
"1","(-7775,8175)","0","pure_quanta","I44";
;
LOCATION"R207"
$SEC"1"
CDS_SEC"1"
VALUE"2.2K"
CDS_LIB"pure_quanta"
WATTAGE"1/16W"
MATERIAL"CHIP"
TOLERANCE"5%"
PACK_TYPE"0402LF"
PART_NUMBER"CS22202JB07";
"B"
$PN"2"42;
"A"
$PN"1"65;
%"Q_RES"
"1","(-7775,8225)","0","pure_quanta","I45";
;
LOCATION"R452"
$SEC"1"
CDS_SEC"1"
VALUE"4.7K"
PACK_TYPE"0402LF"
TOLERANCE"5%"
MATERIAL"CHIP"
WATTAGE"1/16W"
CDS_LIB"pure_quanta"
PART_NUMBER"CS24702JB10";
"B"
$PN"2"42;
"A"
$PN"1"53;
%"Q_RES"
"1","(-7775,8275)","0","pure_quanta","I46";
;
LOCATION"R451"
$SEC"1"
CDS_SEC"1"
VALUE"4.7K"
PACK_TYPE"0402LF"
TOLERANCE"5%"
MATERIAL"CHIP"
WATTAGE"1/16W"
CDS_LIB"pure_quanta"
PART_NUMBER"CS24702JB10";
"B"
$PN"2"42;
"A"
$PN"1"54;
%"Q_RES"
"1","(-7775,8325)","0","pure_quanta","I47";
;
LOCATION"R450"
$SEC"1"
CDS_SEC"1"
VALUE"4.7K"
PACK_TYPE"0402LF"
TOLERANCE"5%"
MATERIAL"CHIP"
WATTAGE"1/16W"
CDS_LIB"pure_quanta"
PART_NUMBER"CS24702JB10";
"B"
$PN"2"42;
"A"
$PN"1"55;
%"Q_RES"
"1","(-7775,8375)","0","pure_quanta","I48";
;
LOCATION"R449"
$SEC"1"
CDS_SEC"1"
VALUE"4.7K"
MATERIAL"EMPTY"
PACK_TYPE"0402LF"
TOLERANCE"5%"
WATTAGE"1/16W"
CDS_LIB"pure_quanta"
PART_NUMBER"CS24702JB10";
"B"
$PN"2"42;
"A"
$PN"1"61;
%"Q_RES"
"1","(-7775,8425)","0","pure_quanta","I49";
;
LOCATION"R448"
$SEC"1"
CDS_SEC"1"
VALUE"4.7K"
MATERIAL"EMPTY"
PACK_TYPE"0402LF"
TOLERANCE"5%"
WATTAGE"1/16W"
CDS_LIB"pure_quanta"
PART_NUMBER"CS24702JB10";
"B"
$PN"2"42;
"A"
$PN"1"62;
%"Q_RES"
"1","(-7775,8675)","0","pure_quanta","I53";
;
LOCATION"R443"
$SEC"1"
CDS_SEC"1"
VALUE"1K"
TOLERANCE"1%"
PACK_TYPE"0402LF"
MATERIAL"CHIP"
WATTAGE"1/16W"
CDS_LIB"pure_quanta"
PART_NUMBER"CS21002FB06";
"B"
$PN"2"42;
"A"
$PN"1"57;
%"Q_RES"
"1","(-7775,8775)","0","pure_quanta","I55";
;
LOCATION"R441"
$SEC"1"
CDS_SEC"1"
VALUE"2.2K"
CDS_LIB"pure_quanta"
WATTAGE"1/16W"
MATERIAL"CHIP"
TOLERANCE"5%"
PACK_TYPE"0402LF"
PART_NUMBER"CS22202JB07";
"B"
$PN"2"42;
"A"
$PN"1"56;
%"Q_RES"
"1","(-7775,8725)","0","pure_quanta","I56";
;
LOCATION"R442"
$SEC"1"
CDS_SEC"1"
VALUE"1K"
TOLERANCE"1%"
PACK_TYPE"0402LF"
MATERIAL"CHIP"
WATTAGE"1/16W"
CDS_LIB"pure_quanta"
PART_NUMBER"CS21002FB06";
"B"
$PN"2"42;
"A"
$PN"1"58;
%"UNIVERSAL_POWER"
"1","(-7400,8000)","0","pure_quanta_power","I57";
;
HDL_POWER"PVDD18_S5_P0"
CDS_LIB"pure_quanta_power";
"A"9;
%"UNIVERSAL_GND"
"1","(-7075,7075)","0","pure_quanta_power","I58";
;
CDS_LIB"pure_quanta_power"
HDL_POWER"GND";
"A"153;
%"Q_RES"
"1","(-7075,7225)","1","pure_quanta","I59";
;
LOCATION"R5027"
$SEC"1"
CDS_SEC"1"
VALUE"4.7K"
MATERIAL"EMPTY"
CDS_LIB"pure_quanta"
WATTAGE"1/16W"
TOLERANCE"5%"
PACK_TYPE"0402LF"
PART_NUMBER"CS24702JB10";
"B"
$PN"2"10;
"A"
$PN"1"153;
%"Q_RES"
"1","(-6925,7225)","1","pure_quanta","I60";
;
LOCATION"R5028"
$SEC"1"
CDS_SEC"1"
VALUE"4.7K"
MATERIAL"EMPTY"
CDS_LIB"pure_quanta"
WATTAGE"1/16W"
TOLERANCE"5%"
PACK_TYPE"0402LF"
PART_NUMBER"CS24702JB10";
"B"
$PN"2"11;
"A"
$PN"1"152;
%"UNIVERSAL_GND"
"1","(-6925,7075)","0","pure_quanta_power","I61";
;
CDS_LIB"pure_quanta_power"
HDL_POWER"GND";
"A"152;
%"Q_RES"
"1","(-6775,7225)","1","pure_quanta","I62";
;
LOCATION"R5029"
$SEC"1"
CDS_SEC"1"
VALUE"4.7K"
MATERIAL"EMPTY"
CDS_LIB"pure_quanta"
WATTAGE"1/16W"
TOLERANCE"5%"
PACK_TYPE"0402LF"
PART_NUMBER"CS24702JB10";
"B"
$PN"2"12;
"A"
$PN"1"151;
%"UNIVERSAL_GND"
"1","(-6775,7075)","0","pure_quanta_power","I63";
;
CDS_LIB"pure_quanta_power"
HDL_POWER"GND";
"A"151;
%"Q_RES"
"1","(-7075,7750)","1","pure_quanta","I64";
;
LOCATION"R446"
$SEC"1"
CDS_SEC"1"
MATERIAL"CHIP"
VALUE"4.7K"
PACK_TYPE"0402LF"
TOLERANCE"5%"
WATTAGE"1/16W"
CDS_LIB"pure_quanta"
PART_NUMBER"CS24702JB10";
"B"
$PN"2"9;
"A"
$PN"1"10;
%"Q_RES"
"1","(-6775,7750)","1","pure_quanta","I65";
;
LOCATION"R447"
$SEC"1"
CDS_SEC"1"
MATERIAL"CHIP"
VALUE"4.7K"
PACK_TYPE"0402LF"
TOLERANCE"5%"
WATTAGE"1/16W"
CDS_LIB"pure_quanta"
PART_NUMBER"CS24702JB10";
"B"
$PN"2"9;
"A"
$PN"1"12;
%"Q_RES"
"1","(-6925,7750)","1","pure_quanta","I66";
;
LOCATION"R445"
$SEC"1"
CDS_SEC"1"
VALUE"4.7K"
MATERIAL"CHIP"
PACK_TYPE"0402LF"
TOLERANCE"5%"
WATTAGE"1/16W"
CDS_LIB"pure_quanta"
PART_NUMBER"CS24702JB10";
"B"
$PN"2"9;
"A"
$PN"1"11;
%"UNIVERSAL_GND"
"1","(-6225,7600)","0","pure_quanta_power","I68";
;
CDS_LIB"pure_quanta_power"
HDL_POWER"GND";
"A"8;
%"Q_RES"
"1","(-7775,8975)","0","pure_quanta","I69";
;
LOCATION"R938"
$SEC"1"
CDS_SEC"1"
VALUE"4.7K"
PACK_TYPE"0402LF"
TOLERANCE"5%"
MATERIAL"CHIP"
WATTAGE"1/16W"
CDS_LIB"pure_quanta"
PART_NUMBER"CS24702JB10";
"B"
$PN"2"42;
"A"
$PN"1"131;
%"UNIVERSAL_POWER"
"1","(-7425,9075)","0","pure_quanta_power","I74";
;
HDL_POWER"PVDD18_S5_P0"
CDS_LIB"pure_quanta_power";
"A"42;
%"Q_RES"
"1","(-6375,9925)","2","pure_quanta","I93";
;
LOCATION"R939"
$SEC"1"
CDS_SEC"1"
VALUE"0"
PACK_TYPE"0402LF"
TOLERANCE"5%"
MATERIAL"CHIP"
WATTAGE"1/16W"
CDS_LIB"pure_quanta"
PART_NUMBER"CS00002JB13";
"B"
$PN"2"124;
"A"
$PN"1"19;
%"Q_RES"
"1","(-6375,9875)","2","pure_quanta","I94";
;
LOCATION"R940"
$SEC"1"
CDS_SEC"1"
VALUE"0"
PACK_TYPE"0402LF"
TOLERANCE"5%"
MATERIAL"CHIP"
WATTAGE"1/16W"
CDS_LIB"pure_quanta"
PART_NUMBER"CS00002JB13";
"B"
$PN"2"76;
"A"
$PN"1"18;
%"Q_RES"
"1","(-6850,10775)","2","pure_quanta","I95";
;
LOCATION"R213"
$SEC"1"
CDS_SEC"1"
VALUE"0"
PACK_TYPE"0402LF"
TOLERANCE"5%"
MATERIAL"CHIP"
WATTAGE"1/16W"
CDS_LIB"pure_quanta"
PART_NUMBER"CS00002JB13";
"B"
$PN"2"145;
"A"
$PN"1"126;
%"Q_RES"
"1","(-6850,10825)","2","pure_quanta","I96";
;
LOCATION"R212"
$SEC"1"
CDS_SEC"1"
VALUE"33"
PACK_TYPE"0402LF"
TOLERANCE"5%"
MATERIAL"CHIP"
WATTAGE"1/16W"
CDS_LIB"pure_quanta"
PART_NUMBER"CS03302JB10";
"B"
$PN"2"25;
"A"
$PN"1"24;
%"Q_RES"
"1","(-6850,10875)","2","pure_quanta","I97";
;
LOCATION"R431"
$SEC"1"
CDS_SEC"1"
VALUE"0"
PACK_TYPE"0402LF"
TOLERANCE"5%"
MATERIAL"CHIP"
WATTAGE"1/16W"
CDS_LIB"pure_quanta"
PART_NUMBER"CS00002JB13";
"B"
$PN"2"144;
"A"
$PN"1"138;
%"Q_RES"
"1","(-6850,10925)","2","pure_quanta","I98";
;
LOCATION"R430"
$SEC"1"
CDS_SEC"1"
VALUE"0"
PACK_TYPE"0402LF"
TOLERANCE"5%"
MATERIAL"CHIP"
WATTAGE"1/16W"
CDS_LIB"pure_quanta"
PART_NUMBER"CS00002JB13";
"B"
$PN"2"143;
"A"
$PN"1"139;
END.
